# T6G (Grand Teton) — schematic netlist excerpt (pin names and nets, part order shuffled) for the footprints in the layout excerpt that follows; sources: Cadence DE-HDL packaged netlist, KiCad conversion of 04192023_DAF0TMB3IC0_F0TG_MB_C_brd_V02_OCP.brd

C699  Q_CAP_DIFFBUS  DIFF BUS_0.22UF 6.3V 20% X6S  pkg C0201  page 67 : \1\ = P5E_CPU1_G1_TX_C_DP<5> ; \2\ = P5E_CPU1_G1_TX_DP<5>
R126  Q_RES  10K 1% CHIP  pkg 0402LF  page 83 : A = FM_APML_MUX2_OE_N ; B = GND
L7  Q_INDUCTOR  BLM21SN300SN1D/5A IND  pkg SMLF  page 345 : \1\ = P1V8_CPU1_RT_1D ; \2\ = P1V8_CPU1_RT2_1A

(kicad_pcb
	(version 20260206)
	(generator "pcbnew")
	(generator_version "10.0")
	(general
		(thickness 1.6)
		(legacy_teardrops no)
	)
	(paper "A4")
	(title_block
		(title "04192023_DAF0TMB3IC0_F0TG_MB_C_brd_V02_OCP.brd")
		(comment 1 "Grand Teton / footprints 4067-4069 of 8354")
	)
	(layers
		(0 "F.Cu" signal "TOP")
		(4 "In1.Cu" signal "GND")
		(6 "In2.Cu" signal "IN1")
		(8 "In3.Cu" signal "GND1")
		(10 "In4.Cu" signal "IN2")
		(12 "In5.Cu" signal "GND2")
		(14 "In6.Cu" signal "IN3")
		(16 "In7.Cu" signal "GND3")
		(18 "In8.Cu" signal "VCC")
		(20 "In9.Cu" signal "VCC1")
		(22 "In10.Cu" signal "GND4")
		(24 "In11.Cu" signal "IN4")
		(26 "In12.Cu" signal "GND5")
		(28 "In13.Cu" signal "IN5")
		(30 "In14.Cu" signal "GND6")
		(32 "In15.Cu" signal "IN6")
		(34 "In16.Cu" signal "GND7")
		(2 "B.Cu" signal "BOTTOM")
		(9 "F.Adhes" user "F.Adhesive")
		(11 "B.Adhes" user "B.Adhesive")
		(13 "F.Paste" user "Package Geometry/Pastemask Top")
		(15 "B.Paste" user "Package Geometry/Pastemask Bottom")
		(5 "F.SilkS" user "Ref Des/Silkscreen Top")
		(7 "B.SilkS" user "Ref Des/Silkscreen Bottom")
		(1 "F.Mask" user "Board Geometry/Soldermask Top")
		(3 "B.Mask" user "Board Geometry/Soldermask Bottom")
		(17 "Dwgs.User" user "User.Drawings")
		(19 "Cmts.User" user "User.Comments")
		(21 "Eco1.User" user "User.Eco1")
		(23 "Eco2.User" user "User.Eco2")
		(25 "Edge.Cuts" user "Board Geometry/Outline")
		(27 "Margin" user)
		(31 "F.CrtYd" user "Package Geometry/Place Bound Top")
		(29 "B.CrtYd" user "Package Geometry/Place Bound Bottom")
		(35 "F.Fab" user "Ref Des/Assembly Top")
		(33 "B.Fab" user "Ref Des/Assembly Bottom")
	)
	(footprint ""
		(layer "F.Cu")
		(at 212.993732 -110.630208 180)
		(property "Reference" "R126"
			(at 0 0 180)
			(layer "F.SilkS")
			(hide yes)
			(effects
				(font
					(size 1.27 1.27)
				)
			)
		)
		(property "Value" ""
			(at 0 0 180)
			(layer "F.Fab")
			(effects
				(font
					(size 1.27 1.27)
				)
			)
		)
		(duplicate_pad_numbers_are_jumpers no)
		(fp_line
			(start 0.7874 0.4064)
			(end -0.7874 0.4064)
			(stroke
				(width 0.1524)
				(type default)
			)
			(layer "F.SilkS")
		)
		(fp_line
			(start 0.7874 -0.4064)
			(end 0.7874 0.4064)
			(stroke
				(width 0.1524)
				(type default)
			)
			(layer "F.SilkS")
		)
		(fp_line
			(start -0.7874 0.4064)
			(end -0.7874 -0.4064)
			(stroke
				(width 0.1524)
				(type default)
			)
			(layer "F.SilkS")
		)
		(fp_line
			(start -0.7874 -0.4064)
			(end 0.7874 -0.4064)
			(stroke
				(width 0.1524)
				(type default)
			)
			(layer "F.SilkS")
		)
		(fp_line
			(start 0.67945 0.3048)
			(end 0.120396 0.3048)
			(stroke
				(width 0.1)
				(type default)
			)
			(layer "F.Fab")
		)
		(fp_line
			(start 0.67945 -0.3048)
			(end 0.67945 0.3048)
			(stroke
				(width 0.1)
				(type default)
			)
			(layer "F.Fab")
		)
		(fp_line
			(start 0.12065 -0.2794)
			(end 0.12065 -0.3048)
			(stroke
				(width 0.1)
				(type default)
			)
			(layer "F.Fab")
		)
		(fp_line
			(start 0.12065 -0.3048)
			(end 0.67945 -0.3048)
			(stroke
				(width 0.1)
				(type default)
			)
			(layer "F.Fab")
		)
		(fp_line
			(start 0.120396 0.3048)
			(end 0.120396 0.2794)
			(stroke
				(width 0.1)
				(type default)
			)
			(layer "F.Fab")
		)
		(fp_line
			(start 0.120396 0.2794)
			(end -0.12065 0.2794)
			(stroke
				(width 0.1)
				(type default)
			)
			(layer "F.Fab")
		)
		(fp_line
			(start -0.12065 0.3048)
			(end -0.67945 0.3048)
			(stroke
				(width 0.1)
				(type default)
			)
			(layer "F.Fab")
		)
		(fp_line
			(start -0.12065 0.2794)
			(end -0.12065 0.3048)
			(stroke
				(width 0.1)
				(type default)
			)
			(layer "F.Fab")
		)
		(fp_line
			(start -0.12065 -0.2794)
			(end 0.12065 -0.2794)
			(stroke
				(width 0.1)
				(type default)
			)
			(layer "F.Fab")
		)
		(fp_line
			(start -0.12065 -0.305054)
			(end -0.12065 -0.2794)
			(stroke
				(width 0.1)
				(type default)
			)
			(layer "F.Fab")
		)
		(fp_line
			(start -0.67945 0.3048)
			(end -0.67945 -0.305054)
			(stroke
				(width 0.1)
				(type default)
			)
			(layer "F.Fab")
		)
		(fp_line
			(start -0.67945 -0.305054)
			(end -0.12065 -0.305054)
			(stroke
				(width 0.1)
				(type default)
			)
			(layer "F.Fab")
		)
		(pad "1" smd circle
			(at -0.40005 0 180)
			(size 0 0)
			(layers "F.Cu" "F.Mask" "F.Paste")
			(net "FM_APML_MUX2_OE_N")
		)
		(pad "2" smd circle
			(at 0.40005 0 180)
			(size 0 0)
			(layers "F.Cu" "F.Mask" "F.Paste")
			(net "GND")
		)
	)
	(footprint ""
		(layer "F.Cu")
		(at 44.668694 -16.099536 90)
		(property "Reference" "C699"
			(at 0 0 90)
			(layer "F.SilkS")
			(hide yes)
			(effects
				(font
					(size 1.27 1.27)
				)
			)
		)
		(property "Value" ""
			(at 0 0 90)
			(layer "F.Fab")
			(effects
				(font
					(size 1.27 1.27)
				)
			)
		)
		(duplicate_pad_numbers_are_jumpers no)
		(fp_line
			(start 0.299974 -0.150114)
			(end 0.299974 0.150114)
			(stroke
				(width 0.1)
				(type default)
			)
			(layer "F.Fab")
		)
		(fp_line
			(start -0.299974 -0.150114)
			(end 0.299974 -0.150114)
			(stroke
				(width 0.1)
				(type default)
			)
			(layer "F.Fab")
		)
		(fp_line
			(start 0.299974 0.150114)
			(end -0.299974 0.150114)
			(stroke
				(width 0.1)
				(type default)
			)
			(layer "F.Fab")
		)
		(fp_line
			(start -0.299974 0.150114)
			(end -0.299974 -0.150114)
			(stroke
				(width 0.1)
				(type default)
			)
			(layer "F.Fab")
		)
		(pad "1" smd rect
			(at -0.2667 0 90)
			(size 0.3048 0.381)
			(layers "F.Cu" "F.Mask" "F.Paste")
			(net "P5E_CPU1_G1_TX_C_DP<5>")
		)
		(pad "2" smd rect
			(at 0.2667 0 90)
			(size 0.3048 0.381)
			(layers "F.Cu" "F.Mask" "F.Paste")
			(net "P5E_CPU1_G1_TX_DP<5>")
		)
	)
	(footprint ""
		(layer "F.Cu")
		(at 170.3324 -384.6068 180)
		(property "Reference" "L7"
			(at 0 0 180)
			(layer "F.SilkS")
			(hide yes)
			(effects
				(font
					(size 1.27 1.27)
				)
			)
		)
		(property "Value" ""
			(at 0 0 180)
			(layer "F.Fab")
			(effects
				(font
					(size 1.27 1.27)
				)
			)
		)
		(duplicate_pad_numbers_are_jumpers no)
		(fp_line
			(start 1.63576 0.8128)
			(end -1.63576 0.8128)
			(stroke
				(width 0.1524)
				(type default)
			)
			(layer "F.SilkS")
		)
		(fp_line
			(start 1.63576 -0.8128)
			(end 1.63576 0.8128)
			(stroke
				(width 0.1524)
				(type default)
			)
			(layer "F.SilkS")
		)
		(fp_line
			(start -1.63576 -0.8128)
			(end 1.63576 -0.8128)
			(stroke
				(width 0.1524)
				(type default)
			)
			(layer "F.SilkS")
		)
		(fp_line
			(start -1.63576 -0.8128)
			(end -1.63576 0.8128)
			(stroke
				(width 0.1524)
				(type default)
			)
			(layer "F.SilkS")
		)
		(fp_line
			(start 1.560576 0.7366)
			(end 1.560576 -0.738632)
			(stroke
				(width 0.1)
				(type default)
			)
			(layer "F.Fab")
		)
		(fp_line
			(start 1.560576 -0.738632)
			(end -1.56083 -0.738632)
			(stroke
				(width 0.1)
				(type default)
			)
			(layer "F.Fab")
		)
		(fp_line
			(start 1.524 0.7366)
			(end 1.560576 0.7366)
			(stroke
				(width 0.1)
				(type default)
			)
			(layer "F.Fab")
		)
		(fp_line
			(start -1.524 0.7366)
			(end 1.524 0.7366)
			(stroke
				(width 0.1)
				(type default)
			)
			(layer "F.Fab")
		)
		(fp_line
			(start -1.56083 0.7366)
			(end -1.524 0.7366)
			(stroke
				(width 0.1)
				(type default)
			)
			(layer "F.Fab")
		)
		(fp_line
			(start -1.56083 -0.738632)
			(end -1.56083 0.7366)
			(stroke
				(width 0.1)
				(type default)
			)
			(layer "F.Fab")
		)
		(pad "1" smd rect
			(at -0.94996 0)
			(size 1.1176 1.3716)
			(layers "F.Cu" "F.Mask" "F.Paste")
			(net "P1V8_CPU1_RT_1D")
		)
		(pad "2" smd rect
			(at 0.94996 0)
			(size 1.1176 1.3716)
			(layers "F.Cu" "F.Mask" "F.Paste")
			(net "P1V8_CPU1_RT2_1A")
		)
	)
)
